(kicad_pcb
	(version 20221018)
	(generator pcbnew)
	(general
    (thickness 1.62)
  )
	(paper "A4")
	(title_block
    (title "ECP5 - Datacenter Secure Control Module (DC-SCM)")
    (date "2024-07-01")
    (rev "1.2.1")
		(comment 9 "footprints 344-351 of 506")
	)
	(layers
    (0 "F.Cu" signal)
    (1 "In1.Cu" power)
    (2 "In2.Cu" signal)
    (3 "In3.Cu" power)
    (4 "In4.Cu" power)
    (5 "In5.Cu" signal)
    (6 "In6.Cu" power)
    (31 "B.Cu" signal)
    (32 "B.Adhes" user "B.Adhesive")
    (33 "F.Adhes" user "F.Adhesive")
    (34 "B.Paste" user)
    (35 "F.Paste" user)
    (36 "B.SilkS" user "B.Silkscreen")
    (37 "F.SilkS" user "F.Silkscreen")
    (38 "B.Mask" user)
    (39 "F.Mask" user)
    (40 "Dwgs.User" user "User.Drawings")
    (41 "Cmts.User" user "User.Comments")
    (42 "Eco1.User" user "User.Eco1")
    (43 "Eco2.User" user "User.Eco2")
    (44 "Edge.Cuts" user)
    (45 "Margin" user)
    (46 "B.CrtYd" user "B.Courtyard")
    (47 "F.CrtYd" user "F.Courtyard")
    (48 "B.Fab" user)
    (49 "F.Fab" user)
  )
	(footprint "antmicro-footprints:C_0402_1005Metric" (layer "B.Cu")
    (at 97.6 118.171428 180)
    (descr "Capacitor SMD 0402")
    (tags "capacitor SMD 0402")
    (property "Author" "Antmicro")
    (property "Dielectric" "")
    (property "License" "Apache-2.0")
    (property "MPN" "C1005X5R1E474M050BB")
    (property "Manufacturer" "TDK")
    (property "Public" "False")
    (property "Sheetfile" "fpga-banks.kicad_sch")
    (property "Sheetname" "FPGA banks")
    (property "Val" "470n")
    (property "Voltage" "")
    (property "ki_description" "SMD Multilayer Ceramic Capacitor, 0.47 µF, 25 V, 0402 [1005 Metric], ± 20%, X5R, C")
    (property "ki_keywords" "0402, SMT, CAPACITOR, PASSIVE, CERAMIC, MLCC")
    (attr smd)
    (fp_text reference "C238" (at 2.4 0.221428) (layer "B.SilkS")
        (effects (font (size 0.7 0.7) (thickness 0.127)) (justify mirror))
    )
    (fp_text value "C_470n_0402" (at 0 -1.17) (layer "B.Fab")
        (effects (font (size 1 1) (thickness 0.15)) (justify mirror))
    )
    (fp_text user "License: Apache-2.0" (at -0.939 -5.799) (layer "B.Fab") hide
        (effects (font (size 0.7 0.7) (thickness 0.15)) (justify left bottom mirror))
    )
    (fp_text user "${REFERENCE}" (at 0 0) (layer "B.Fab")
        (effects (font (size 0.25 0.25) (thickness 0.04)) (justify mirror))
    )
    (fp_text user "Author: Antmicro" (at -0.939 -3.399) (layer "B.Fab") hide
        (effects (font (size 0.7 0.7) (thickness 0.15)) (justify left bottom mirror))
    )
    (fp_rect (start -0.925 0.47) (end 0.925 -0.47)
      (stroke (width 0.05) (type default)) (fill none) (layer "B.CrtYd"))
    (fp_line (start -0.494 -0.248) (end -0.494 0.25)
      (stroke (width 0.15) (type solid)) (layer "B.Fab"))
    (fp_line (start -0.494 0.25) (end 0.504 0.25)
      (stroke (width 0.15) (type solid)) (layer "B.Fab"))
    (fp_line (start 0.504 -0.248) (end -0.494 -0.248)
      (stroke (width 0.15) (type solid)) (layer "B.Fab"))
    (fp_line (start 0.504 0.25) (end 0.504 -0.248)
      (stroke (width 0.15) (type solid)) (layer "B.Fab"))
    (pad "1" smd roundrect (at -0.48 0 180) (size 0.59 0.64) (layers "B.Cu" "B.Paste" "B.Mask") (roundrect_rratio 0.25)
      (net 2 "VCC3V3") (pintype "passive"))
    (pad "2" smd roundrect (at 0.48 0 180) (size 0.59 0.64) (layers "B.Cu" "B.Paste" "B.Mask") (roundrect_rratio 0.25)
      (net 1 "GND") (pintype "passive"))
  )
	(footprint "antmicro-footprints:C_0402_1005Metric" (layer "B.Cu")
    (at 97.6 120.242856 180)
    (descr "Capacitor SMD 0402")
    (tags "capacitor SMD 0402")
    (property "Author" "Antmicro")
    (property "Dielectric" "")
    (property "License" "Apache-2.0")
    (property "MPN" "C1005X5R1E474M050BB")
    (property "Manufacturer" "TDK")
    (property "Public" "False")
    (property "Sheetfile" "fpga-banks.kicad_sch")
    (property "Sheetname" "FPGA banks")
    (property "Val" "470n")
    (property "Voltage" "")
    (property "ki_description" "SMD Multilayer Ceramic Capacitor, 0.47 µF, 25 V, 0402 [1005 Metric], ± 20%, X5R, C")
    (property "ki_keywords" "0402, SMT, CAPACITOR, PASSIVE, CERAMIC, MLCC")
    (attr smd)
    (fp_text reference "C239" (at 2.4 0.192856) (layer "B.SilkS")
        (effects (font (size 0.7 0.7) (thickness 0.127)) (justify mirror))
    )
    (fp_text value "C_470n_0402" (at 0 -1.17) (layer "B.Fab")
        (effects (font (size 1 1) (thickness 0.15)) (justify mirror))
    )
    (fp_text user "License: Apache-2.0" (at -0.939 -5.799) (layer "B.Fab") hide
        (effects (font (size 0.7 0.7) (thickness 0.15)) (justify left bottom mirror))
    )
    (fp_text user "${REFERENCE}" (at 0 0) (layer "B.Fab")
        (effects (font (size 0.25 0.25) (thickness 0.04)) (justify mirror))
    )
    (fp_text user "Author: Antmicro" (at -0.939 -3.399) (layer "B.Fab") hide
        (effects (font (size 0.7 0.7) (thickness 0.15)) (justify left bottom mirror))
    )
    (fp_rect (start -0.925 0.47) (end 0.925 -0.47)
      (stroke (width 0.05) (type default)) (fill none) (layer "B.CrtYd"))
    (fp_line (start -0.494 -0.248) (end -0.494 0.25)
      (stroke (width 0.15) (type solid)) (layer "B.Fab"))
    (fp_line (start -0.494 0.25) (end 0.504 0.25)
      (stroke (width 0.15) (type solid)) (layer "B.Fab"))
    (fp_line (start 0.504 -0.248) (end -0.494 -0.248)
      (stroke (width 0.15) (type solid)) (layer "B.Fab"))
    (fp_line (start 0.504 0.25) (end 0.504 -0.248)
      (stroke (width 0.15) (type solid)) (layer "B.Fab"))
    (pad "1" smd roundrect (at -0.48 0 180) (size 0.59 0.64) (layers "B.Cu" "B.Paste" "B.Mask") (roundrect_rratio 0.25)
      (net 2 "VCC3V3") (pintype "passive"))
    (pad "2" smd roundrect (at 0.48 0 180) (size 0.59 0.64) (layers "B.Cu" "B.Paste" "B.Mask") (roundrect_rratio 0.25)
      (net 1 "GND") (pintype "passive"))
  )
	(footprint "antmicro-footprints:FB_0603_1608Metric" (layer "B.Cu")
    (at 98.76 128.995 -90)
    (property "Author" "Antmicro")
    (property "Current" "")
    (property "License" "Apache-2.0")
    (property "MPN" "BLM18PG121SN1D")
    (property "Manufacturer" "Murata")
    (property "Public" "False")
    (property "Sheetfile" "fpga-power-supply.kicad_sch")
    (property "Sheetname" "FPGA power supply")
    (property "Val" "120Z/2A")
    (property "ki_description" "Ferrite Bead, 0603 [1608 Metric], 120 ohm, 2 A, BLM18P, 0.05 ohm, ± 25%, DC power line")
    (property "ki_keywords" "0603, SMT, FERRITE BEAD, PASSIVE")
    (attr smd)
    (fp_text reference "FB4" (at 21.52 -1.02 90) (layer "B.SilkS")
        (effects (font (size 0.7 0.7) (thickness 0.127)) (justify mirror))
    )
    (fp_text value "FB_120Z_2A_Murata-BLM18PG_0603" (at 0 -1.9 90) (layer "B.Fab")
        (effects (font (size 1 1) (thickness 0.15)) (justify mirror))
    )
    (fp_text user "${REFERENCE}" (at -1.653 -4.6 90) (layer "B.Fab") hide
        (effects (font (size 0.7 0.7) (thickness 0.15)) (justify left bottom mirror))
    )
    (fp_text user "License: Apache-2.0" (at -1.653 -5.9 90) (layer "B.Fab") hide
        (effects (font (size 0.7 0.7) (thickness 0.15)) (justify left bottom mirror))
    )
    (fp_text user "Author: Antmicro" (at -1.653 -3.162 90) (layer "B.Fab") hide
        (effects (font (size 0.7 0.7) (thickness 0.15)) (justify left bottom mirror))
    )
    (fp_line (start -0.15 -0.4) (end 0.15 -0.4)
      (stroke (width 0.15) (type solid)) (layer "B.SilkS"))
    (fp_line (start -0.15 0.4) (end 0.15 0.4)
      (stroke (width 0.15) (type solid)) (layer "B.SilkS"))
    (fp_rect (start -1.25 0.65) (end 1.25 -0.65)
      (stroke (width 0.05) (type solid)) (fill none) (layer "B.CrtYd"))
    (fp_line (start -0.803 -0.406) (end -0.803 0.408)
      (stroke (width 0.15) (type solid)) (layer "B.Fab"))
    (fp_line (start 0.8 -0.406) (end -0.803 -0.406)
      (stroke (width 0.15) (type solid)) (layer "B.Fab"))
    (fp_line (start 0.8 0.408) (end -0.803 0.408)
      (stroke (width 0.15) (type solid)) (layer "B.Fab"))
    (fp_line (start 0.8 0.408) (end 0.8 -0.406)
      (stroke (width 0.15) (type solid)) (layer "B.Fab"))
    (pad "1" smd roundrect (at -0.7 0 270) (size 0.8 1) (layers "B.Cu" "B.Paste" "B.Mask") (roundrect_rratio 0.2)
      (net 211 "VCC1V2") (pintype "passive"))
    (pad "2" smd roundrect (at 0.7 0 270) (size 0.8 1) (layers "B.Cu" "B.Paste" "B.Mask") (roundrect_rratio 0.2)
      (net 302 "/FPGA power supply/VCCA0") (pintype "passive"))
  )
	(footprint "antmicro-footprints:FB_0603_1608Metric" (layer "B.Cu")
    (at 99.8 127.075)
    (property "Author" "Antmicro")
    (property "Current" "")
    (property "License" "Apache-2.0")
    (property "MPN" "BLM18PG121SN1D")
    (property "Manufacturer" "Murata")
    (property "Public" "False")
    (property "Sheetfile" "fpga-power-supply.kicad_sch")
    (property "Sheetname" "FPGA power supply")
    (property "Val" "120Z/2A")
    (property "ki_description" "Ferrite Bead, 0603 [1608 Metric], 120 ohm, 2 A, BLM18P, 0.05 ohm, ± 25%, DC power line")
    (property "ki_keywords" "0603, SMT, FERRITE BEAD, PASSIVE")
    (attr smd)
    (fp_text reference "FB5" (at 0.15 21.71) (layer "B.SilkS")
        (effects (font (size 0.7 0.7) (thickness 0.127)) (justify mirror))
    )
    (fp_text value "FB_120Z_2A_Murata-BLM18PG_0603" (at 0 -1.9) (layer "B.Fab")
        (effects (font (size 1 1) (thickness 0.15)) (justify mirror))
    )
    (fp_text user "${REFERENCE}" (at -1.653 -4.6 180) (layer "B.Fab") hide
        (effects (font (size 0.7 0.7) (thickness 0.15)) (justify left bottom mirror))
    )
    (fp_text user "Author: Antmicro" (at -1.653 -3.162 180) (layer "B.Fab") hide
        (effects (font (size 0.7 0.7) (thickness 0.15)) (justify left bottom mirror))
    )
    (fp_text user "License: Apache-2.0" (at -1.653 -5.9 180) (layer "B.Fab") hide
        (effects (font (size 0.7 0.7) (thickness 0.15)) (justify left bottom mirror))
    )
    (fp_line (start -0.15 -0.4) (end 0.15 -0.4)
      (stroke (width 0.15) (type solid)) (layer "B.SilkS"))
    (fp_line (start -0.15 0.4) (end 0.15 0.4)
      (stroke (width 0.15) (type solid)) (layer "B.SilkS"))
    (fp_rect (start -1.25 0.65) (end 1.25 -0.65)
      (stroke (width 0.05) (type solid)) (fill none) (layer "B.CrtYd"))
    (fp_line (start -0.803 -0.406) (end -0.803 0.408)
      (stroke (width 0.15) (type solid)) (layer "B.Fab"))
    (fp_line (start 0.8 -0.406) (end -0.803 -0.406)
      (stroke (width 0.15) (type solid)) (layer "B.Fab"))
    (fp_line (start 0.8 0.408) (end -0.803 0.408)
      (stroke (width 0.15) (type solid)) (layer "B.Fab"))
    (fp_line (start 0.8 0.408) (end 0.8 -0.406)
      (stroke (width 0.15) (type solid)) (layer "B.Fab"))
    (pad "1" smd roundrect (at -0.7 0) (size 0.8 1) (layers "B.Cu" "B.Paste" "B.Mask") (roundrect_rratio 0.2)
      (net 211 "VCC1V2") (pintype "passive"))
    (pad "2" smd roundrect (at 0.7 0) (size 0.8 1) (layers "B.Cu" "B.Paste" "B.Mask") (roundrect_rratio 0.2)
      (net 5 "/FPGA power supply/VCCHTX0") (pintype "passive"))
  )
	(footprint "antmicro-footprints:FB_0603_1608Metric" (layer "B.Cu")
    (at 110.7 127.1 180)
    (property "Author" "Antmicro")
    (property "Current" "")
    (property "License" "Apache-2.0")
    (property "MPN" "BLM18PG121SN1D")
    (property "Manufacturer" "Murata")
    (property "Public" "False")
    (property "Sheetfile" "fpga-power-supply.kicad_sch")
    (property "Sheetname" "FPGA power supply")
    (property "Val" "120Z/2A")
    (property "ki_description" "Ferrite Bead, 0603 [1608 Metric], 120 ohm, 2 A, BLM18P, 0.05 ohm, ± 25%, DC power line")
    (property "ki_keywords" "0603, SMT, FERRITE BEAD, PASSIVE")
    (attr smd)
    (fp_text reference "FB6" (at -3.95 -0.2) (layer "B.SilkS")
        (effects (font (size 0.7 0.7) (thickness 0.127)) (justify mirror))
    )
    (fp_text value "FB_120Z_2A_Murata-BLM18PG_0603" (at 0 -1.9) (layer "B.Fab")
        (effects (font (size 1 1) (thickness 0.15)) (justify mirror))
    )
    (fp_text user "License: Apache-2.0" (at -1.653 -5.9) (layer "B.Fab") hide
        (effects (font (size 0.7 0.7) (thickness 0.15)) (justify left bottom mirror))
    )
    (fp_text user "${REFERENCE}" (at -1.653 -4.6) (layer "B.Fab") hide
        (effects (font (size 0.7 0.7) (thickness 0.15)) (justify left bottom mirror))
    )
    (fp_text user "Author: Antmicro" (at -1.653 -3.162) (layer "B.Fab") hide
        (effects (font (size 0.7 0.7) (thickness 0.15)) (justify left bottom mirror))
    )
    (fp_line (start -0.15 -0.4) (end 0.15 -0.4)
      (stroke (width 0.15) (type solid)) (layer "B.SilkS"))
    (fp_line (start -0.15 0.4) (end 0.15 0.4)
      (stroke (width 0.15) (type solid)) (layer "B.SilkS"))
    (fp_rect (start -1.25 0.65) (end 1.25 -0.65)
      (stroke (width 0.05) (type solid)) (fill none) (layer "B.CrtYd"))
    (fp_line (start -0.803 -0.406) (end -0.803 0.408)
      (stroke (width 0.15) (type solid)) (layer "B.Fab"))
    (fp_line (start 0.8 -0.406) (end -0.803 -0.406)
      (stroke (width 0.15) (type solid)) (layer "B.Fab"))
    (fp_line (start 0.8 0.408) (end -0.803 0.408)
      (stroke (width 0.15) (type solid)) (layer "B.Fab"))
    (fp_line (start 0.8 0.408) (end 0.8 -0.406)
      (stroke (width 0.15) (type solid)) (layer "B.Fab"))
    (pad "1" smd roundrect (at -0.7 0 180) (size 0.8 1) (layers "B.Cu" "B.Paste" "B.Mask") (roundrect_rratio 0.2)
      (net 211 "VCC1V2") (pintype "passive"))
    (pad "2" smd roundrect (at 0.7 0 180) (size 0.8 1) (layers "B.Cu" "B.Paste" "B.Mask") (roundrect_rratio 0.2)
      (net 6 "/FPGA power supply/VCCHTX1") (pintype "passive"))
  )
	(footprint "antmicro-footprints:FB_0603_1608Metric" (layer "B.Cu")
    (at 111.2 129.15 90)
    (property "Author" "Antmicro")
    (property "Current" "")
    (property "License" "Apache-2.0")
    (property "MPN" "BLM18PG121SN1D")
    (property "Manufacturer" "Murata")
    (property "Public" "False")
    (property "Sheetfile" "fpga-power-supply.kicad_sch")
    (property "Sheetname" "FPGA power supply")
    (property "Val" "120Z/2A")
    (property "ki_description" "Ferrite Bead, 0603 [1608 Metric], 120 ohm, 2 A, BLM18P, 0.05 ohm, ± 25%, DC power line")
    (property "ki_keywords" "0603, SMT, FERRITE BEAD, PASSIVE")
    (attr smd)
    (fp_text reference "FB7" (at 1.015 1.92 270) (layer "B.SilkS")
        (effects (font (size 0.7 0.7) (thickness 0.127)) (justify mirror))
    )
    (fp_text value "FB_120Z_2A_Murata-BLM18PG_0603" (at 0 -1.9 90) (layer "B.Fab")
        (effects (font (size 1 1) (thickness 0.15)) (justify mirror))
    )
    (fp_text user "License: Apache-2.0" (at -1.653 -5.9 270) (layer "B.Fab") hide
        (effects (font (size 0.7 0.7) (thickness 0.15)) (justify left bottom mirror))
    )
    (fp_text user "Author: Antmicro" (at -1.653 -3.162 270) (layer "B.Fab") hide
        (effects (font (size 0.7 0.7) (thickness 0.15)) (justify left bottom mirror))
    )
    (fp_text user "${REFERENCE}" (at -1.653 -4.6 270) (layer "B.Fab") hide
        (effects (font (size 0.7 0.7) (thickness 0.15)) (justify left bottom mirror))
    )
    (fp_line (start -0.15 -0.4) (end 0.15 -0.4)
      (stroke (width 0.15) (type solid)) (layer "B.SilkS"))
    (fp_line (start -0.15 0.4) (end 0.15 0.4)
      (stroke (width 0.15) (type solid)) (layer "B.SilkS"))
    (fp_rect (start -1.25 0.65) (end 1.25 -0.65)
      (stroke (width 0.05) (type solid)) (fill none) (layer "B.CrtYd"))
    (fp_line (start -0.803 -0.406) (end -0.803 0.408)
      (stroke (width 0.15) (type solid)) (layer "B.Fab"))
    (fp_line (start 0.8 -0.406) (end -0.803 -0.406)
      (stroke (width 0.15) (type solid)) (layer "B.Fab"))
    (fp_line (start 0.8 0.408) (end -0.803 0.408)
      (stroke (width 0.15) (type solid)) (layer "B.Fab"))
    (fp_line (start 0.8 0.408) (end 0.8 -0.406)
      (stroke (width 0.15) (type solid)) (layer "B.Fab"))
    (pad "1" smd roundrect (at -0.7 0 90) (size 0.8 1) (layers "B.Cu" "B.Paste" "B.Mask") (roundrect_rratio 0.2)
      (net 303 "/FPGA power supply/VCCA1") (pintype "passive"))
    (pad "2" smd roundrect (at 0.7 0 90) (size 0.8 1) (layers "B.Cu" "B.Paste" "B.Mask") (roundrect_rratio 0.2)
      (net 211 "VCC1V2") (pintype "passive"))
  )
	(footprint "antmicro-footprints:FB_0603_1608Metric" (layer "B.Cu")
    (at 113.8 132.55 -90)
    (property "Author" "Antmicro")
    (property "Current" "")
    (property "License" "Apache-2.0")
    (property "MPN" "BLM18PG121SN1D")
    (property "Manufacturer" "Murata")
    (property "Public" "False")
    (property "Sheetfile" "fpga-power-supply.kicad_sch")
    (property "Sheetname" "FPGA power supply")
    (property "Val" "120Z/2A")
    (property "ki_description" "Ferrite Bead, 0603 [1608 Metric], 120 ohm, 2 A, BLM18P, 0.05 ohm, ± 25%, DC power line")
    (property "ki_keywords" "0603, SMT, FERRITE BEAD, PASSIVE")
    (attr smd)
    (fp_text reference "FB8" (at 1.365 -1.34 90) (layer "B.SilkS")
        (effects (font (size 0.7 0.7) (thickness 0.127)) (justify mirror))
    )
    (fp_text value "FB_120Z_2A_Murata-BLM18PG_0603" (at 0 -1.9 90) (layer "B.Fab")
        (effects (font (size 1 1) (thickness 0.15)) (justify mirror))
    )
    (fp_text user "Author: Antmicro" (at -1.653 -3.162 90) (layer "B.Fab") hide
        (effects (font (size 0.7 0.7) (thickness 0.15)) (justify left bottom mirror))
    )
    (fp_text user "${REFERENCE}" (at -1.653 -4.6 90) (layer "B.Fab") hide
        (effects (font (size 0.7 0.7) (thickness 0.15)) (justify left bottom mirror))
    )
    (fp_text user "License: Apache-2.0" (at -1.653 -5.9 90) (layer "B.Fab") hide
        (effects (font (size 0.7 0.7) (thickness 0.15)) (justify left bottom mirror))
    )
    (fp_line (start -0.15 -0.4) (end 0.15 -0.4)
      (stroke (width 0.15) (type solid)) (layer "B.SilkS"))
    (fp_line (start -0.15 0.4) (end 0.15 0.4)
      (stroke (width 0.15) (type solid)) (layer "B.SilkS"))
    (fp_rect (start -1.25 0.65) (end 1.25 -0.65)
      (stroke (width 0.05) (type solid)) (fill none) (layer "B.CrtYd"))
    (fp_line (start -0.803 -0.406) (end -0.803 0.408)
      (stroke (width 0.15) (type solid)) (layer "B.Fab"))
    (fp_line (start 0.8 -0.406) (end -0.803 -0.406)
      (stroke (width 0.15) (type solid)) (layer "B.Fab"))
    (fp_line (start 0.8 0.408) (end -0.803 0.408)
      (stroke (width 0.15) (type solid)) (layer "B.Fab"))
    (fp_line (start 0.8 0.408) (end 0.8 -0.406)
      (stroke (width 0.15) (type solid)) (layer "B.Fab"))
    (pad "1" smd roundrect (at -0.7 0 270) (size 0.8 1) (layers "B.Cu" "B.Paste" "B.Mask") (roundrect_rratio 0.2)
      (net 304 "/FPGA power supply/VCCAUX") (pintype "passive"))
    (pad "2" smd roundrect (at 0.7 0 270) (size 0.8 1) (layers "B.Cu" "B.Paste" "B.Mask") (roundrect_rratio 0.2)
      (net 225 "VCC2V5") (pintype "passive"))
  )
	(footprint "antmicro-footprints:C_0402_1005Metric" (layer "B.Cu")
    (at 105.55 127.4 90)
    (descr "Capacitor SMD 0402")
    (tags "capacitor SMD 0402")
    (property "Author" "Antmicro")
    (property "Dielectric" "X5R")
    (property "License" "Apache-2.0")
    (property "MPN" "GRM155R61H104KE14D")
    (property "Manufacturer" "Murata")
    (property "Public" "False")
    (property "Sheetfile" "fpga-power-supply.kicad_sch")
    (property "Sheetname" "FPGA power supply")
    (property "Val" "100n")
    (property "Voltage" "50V")
    (property "ki_description" "SMD Multilayer Ceramic Capacitor, 0.1 µF, 50 V, 0402 [1005 Metric], ± 10%, X5R, GRM Series")
    (property "ki_keywords" "0402, SMT, CAPACITOR, PASSIVE, CERAMIC, MLCC")
    (attr smd)
    (fp_text reference "C139" (at 22.8 0.05 90) (layer "B.SilkS")
        (effects (font (size 0.7 0.7) (thickness 0.127)) (justify mirror))
    )
    (fp_text value "C_100n_0402" (at 0 -1.17 90) (layer "B.Fab")
        (effects (font (size 1 1) (thickness 0.15)) (justify mirror))
    )
    (fp_text user "${REFERENCE}" (at 0 0 90) (layer "B.Fab")
        (effects (font (size 0.25 0.25) (thickness 0.04)) (justify mirror))
    )
    (fp_text user "Author: Antmicro" (at -0.939 -3.399 270) (layer "B.Fab") hide
        (effects (font (size 0.7 0.7) (thickness 0.15)) (justify left bottom mirror))
    )
    (fp_text user "License: Apache-2.0" (at -0.939 -5.799 270) (layer "B.Fab") hide
        (effects (font (size 0.7 0.7) (thickness 0.15)) (justify left bottom mirror))
    )
    (fp_rect (start -0.925 0.47) (end 0.925 -0.47)
      (stroke (width 0.05) (type default)) (fill none) (layer "B.CrtYd"))
    (fp_line (start -0.494 -0.248) (end -0.494 0.25)
      (stroke (width 0.15) (type solid)) (layer "B.Fab"))
    (fp_line (start -0.494 0.25) (end 0.504 0.25)
      (stroke (width 0.15) (type solid)) (layer "B.Fab"))
    (fp_line (start 0.504 -0.248) (end -0.494 -0.248)
      (stroke (width 0.15) (type solid)) (layer "B.Fab"))
    (fp_line (start 0.504 0.25) (end 0.504 -0.248)
      (stroke (width 0.15) (type solid)) (layer "B.Fab"))
    (pad "1" smd roundrect (at -0.48 0 90) (size 0.59 0.64) (layers "B.Cu" "B.Paste" "B.Mask") (roundrect_rratio 0.25)
      (net 1 "GND") (pintype "passive"))
    (pad "2" smd roundrect (at 0.48 0 90) (size 0.59 0.64) (layers "B.Cu" "B.Paste" "B.Mask") (roundrect_rratio 0.25)
      (net 5 "/FPGA power supply/VCCHTX0") (pintype "passive"))
  )
)
